(kicad_pcb
	(version 20260206)
	(generator "pcbnew")
	(generator_version "10.0")
	(general
		(thickness 1.6)
		(legacy_teardrops no)
	)
	(paper "A4")
	(title_block
		(title "03242023_DA0F0TMBIJ0_F0T_Motherboard_J_brd_V01_OCP.brd")
		(comment 1 "Grand Teton / footprints 543-549 of 6105")
	)
	(layers
		(0 "F.Cu" signal "TOP")
		(4 "In1.Cu" signal "GND")
		(6 "In2.Cu" signal "IN1")
		(8 "In3.Cu" signal "GND1")
		(10 "In4.Cu" signal "IN2")
		(12 "In5.Cu" signal "GND2")
		(14 "In6.Cu" signal "IN3")
		(16 "In7.Cu" signal "GND3")
		(18 "In8.Cu" signal "VCC")
		(20 "In9.Cu" signal "VCC1")
		(22 "In10.Cu" signal "GND4")
		(24 "In11.Cu" signal "IN4")
		(26 "In12.Cu" signal "GND5")
		(28 "In13.Cu" signal "IN5")
		(30 "In14.Cu" signal "GND6")
		(32 "In15.Cu" signal "IN6")
		(34 "In16.Cu" signal "GND7")
		(2 "B.Cu" signal "BOTTOM")
		(9 "F.Adhes" user "F.Adhesive")
		(11 "B.Adhes" user "B.Adhesive")
		(13 "F.Paste" user "Package Geometry/Pastemask Top")
		(15 "B.Paste" user "Package Geometry/Pastemask Bottom")
		(5 "F.SilkS" user "Ref Des/Silkscreen Top")
		(7 "B.SilkS" user "Ref Des/Silkscreen Bottom")
		(1 "F.Mask" user "Board Geometry/Soldermask Top")
		(3 "B.Mask" user "Board Geometry/Soldermask Bottom")
		(17 "Dwgs.User" user "User.Drawings")
		(19 "Cmts.User" user "User.Comments")
		(21 "Eco1.User" user "User.Eco1")
		(23 "Eco2.User" user "User.Eco2")
		(25 "Edge.Cuts" user "Board Geometry/Outline")
		(27 "Margin" user)
		(31 "F.CrtYd" user "Package Geometry/Place Bound Top")
		(29 "B.CrtYd" user "Package Geometry/Place Bound Bottom")
		(35 "F.Fab" user "Ref Des/Assembly Top")
		(33 "B.Fab" user "Ref Des/Assembly Bottom")
	)
	(footprint ""
		(layer "F.Cu")
		(at 22.809454 -113.415826 180)
		(property "Reference" "R1792"
			(at 0 0 180)
			(layer "F.SilkS")
			(hide yes)
			(effects
				(font
					(size 1.27 1.27)
				)
			)
		)
		(property "Value" ""
			(at 0 0 180)
			(layer "F.Fab")
			(effects
				(font
					(size 1.27 1.27)
				)
			)
		)
		(duplicate_pad_numbers_are_jumpers no)
		(fp_line
			(start 0.7874 0.4064)
			(end -0.7874 0.4064)
			(stroke
				(width 0.1524)
				(type default)
			)
			(layer "F.SilkS")
		)
		(fp_line
			(start 0.7874 -0.4064)
			(end 0.7874 0.4064)
			(stroke
				(width 0.1524)
				(type default)
			)
			(layer "F.SilkS")
		)
		(fp_line
			(start -0.7874 0.4064)
			(end -0.7874 -0.4064)
			(stroke
				(width 0.1524)
				(type default)
			)
			(layer "F.SilkS")
		)
		(fp_line
			(start -0.7874 -0.4064)
			(end 0.7874 -0.4064)
			(stroke
				(width 0.1524)
				(type default)
			)
			(layer "F.SilkS")
		)
		(fp_line
			(start 0.67945 0.3048)
			(end 0.120396 0.3048)
			(stroke
				(width 0.1)
				(type default)
			)
			(layer "F.Fab")
		)
		(fp_line
			(start 0.67945 -0.3048)
			(end 0.67945 0.3048)
			(stroke
				(width 0.1)
				(type default)
			)
			(layer "F.Fab")
		)
		(fp_line
			(start 0.12065 -0.2794)
			(end 0.12065 -0.3048)
			(stroke
				(width 0.1)
				(type default)
			)
			(layer "F.Fab")
		)
		(fp_line
			(start 0.12065 -0.3048)
			(end 0.67945 -0.3048)
			(stroke
				(width 0.1)
				(type default)
			)
			(layer "F.Fab")
		)
		(fp_line
			(start 0.120396 0.3048)
			(end 0.120396 0.2794)
			(stroke
				(width 0.1)
				(type default)
			)
			(layer "F.Fab")
		)
		(fp_line
			(start 0.120396 0.2794)
			(end -0.12065 0.2794)
			(stroke
				(width 0.1)
				(type default)
			)
			(layer "F.Fab")
		)
		(fp_line
			(start -0.12065 0.3048)
			(end -0.67945 0.3048)
			(stroke
				(width 0.1)
				(type default)
			)
			(layer "F.Fab")
		)
		(fp_line
			(start -0.12065 0.2794)
			(end -0.12065 0.3048)
			(stroke
				(width 0.1)
				(type default)
			)
			(layer "F.Fab")
		)
		(fp_line
			(start -0.12065 -0.2794)
			(end 0.12065 -0.2794)
			(stroke
				(width 0.1)
				(type default)
			)
			(layer "F.Fab")
		)
		(fp_line
			(start -0.12065 -0.305054)
			(end -0.12065 -0.2794)
			(stroke
				(width 0.1)
				(type default)
			)
			(layer "F.Fab")
		)
		(fp_line
			(start -0.67945 0.3048)
			(end -0.67945 -0.305054)
			(stroke
				(width 0.1)
				(type default)
			)
			(layer "F.Fab")
		)
		(fp_line
			(start -0.67945 -0.305054)
			(end -0.12065 -0.305054)
			(stroke
				(width 0.1)
				(type default)
			)
			(layer "F.Fab")
		)
		(pad "1" smd circle
			(at -0.40005 0 180)
			(size 0 0)
			(layers "F.Cu" "F.Mask" "F.Paste")
			(net "SMB_VR_3V3AUX_SDA_R1")
		)
		(pad "2" smd circle
			(at 0.40005 0 180)
			(size 0 0)
			(layers "F.Cu" "F.Mask" "F.Paste")
			(net "SMB_SEN_MAM_3V3AUX_SDA")
		)
	)
	(footprint ""
		(layer "F.Cu")
		(at 366.3696 -408.1272)
		(property "Reference" "R4737"
			(at 0 0 0)
			(layer "F.SilkS")
			(hide yes)
			(effects
				(font
					(size 1.27 1.27)
				)
			)
		)
		(property "Value" ""
			(at 0 0 0)
			(layer "F.Fab")
			(effects
				(font
					(size 1.27 1.27)
				)
			)
		)
		(duplicate_pad_numbers_are_jumpers no)
		(fp_line
			(start -0.7874 -0.4064)
			(end 0.7874 -0.4064)
			(stroke
				(width 0.1524)
				(type default)
			)
			(layer "F.SilkS")
		)
		(fp_line
			(start -0.7874 0.4064)
			(end -0.7874 -0.4064)
			(stroke
				(width 0.1524)
				(type default)
			)
			(layer "F.SilkS")
		)
		(fp_line
			(start 0.7874 -0.4064)
			(end 0.7874 0.4064)
			(stroke
				(width 0.1524)
				(type default)
			)
			(layer "F.SilkS")
		)
		(fp_line
			(start 0.7874 0.4064)
			(end -0.7874 0.4064)
			(stroke
				(width 0.1524)
				(type default)
			)
			(layer "F.SilkS")
		)
		(fp_line
			(start -0.67945 -0.305054)
			(end -0.12065 -0.305054)
			(stroke
				(width 0.1)
				(type default)
			)
			(layer "F.Fab")
		)
		(fp_line
			(start -0.67945 0.3048)
			(end -0.67945 -0.305054)
			(stroke
				(width 0.1)
				(type default)
			)
			(layer "F.Fab")
		)
		(fp_line
			(start -0.12065 -0.305054)
			(end -0.12065 -0.2794)
			(stroke
				(width 0.1)
				(type default)
			)
			(layer "F.Fab")
		)
		(fp_line
			(start -0.12065 -0.2794)
			(end 0.12065 -0.2794)
			(stroke
				(width 0.1)
				(type default)
			)
			(layer "F.Fab")
		)
		(fp_line
			(start -0.12065 0.2794)
			(end -0.12065 0.3048)
			(stroke
				(width 0.1)
				(type default)
			)
			(layer "F.Fab")
		)
		(fp_line
			(start -0.12065 0.3048)
			(end -0.67945 0.3048)
			(stroke
				(width 0.1)
				(type default)
			)
			(layer "F.Fab")
		)
		(fp_line
			(start 0.120396 0.2794)
			(end -0.12065 0.2794)
			(stroke
				(width 0.1)
				(type default)
			)
			(layer "F.Fab")
		)
		(fp_line
			(start 0.120396 0.3048)
			(end 0.120396 0.2794)
			(stroke
				(width 0.1)
				(type default)
			)
			(layer "F.Fab")
		)
		(fp_line
			(start 0.12065 -0.3048)
			(end 0.67945 -0.3048)
			(stroke
				(width 0.1)
				(type default)
			)
			(layer "F.Fab")
		)
		(fp_line
			(start 0.12065 -0.2794)
			(end 0.12065 -0.3048)
			(stroke
				(width 0.1)
				(type default)
			)
			(layer "F.Fab")
		)
		(fp_line
			(start 0.67945 -0.3048)
			(end 0.67945 0.3048)
			(stroke
				(width 0.1)
				(type default)
			)
			(layer "F.Fab")
		)
		(fp_line
			(start 0.67945 0.3048)
			(end 0.120396 0.3048)
			(stroke
				(width 0.1)
				(type default)
			)
			(layer "F.Fab")
		)
		(pad "1" smd circle
			(at -0.40005 0)
			(size 0 0)
			(layers "F.Cu" "F.Mask" "F.Paste")
			(net "P3V3_AUX")
		)
		(pad "2" smd circle
			(at 0.40005 0)
			(size 0 0)
			(layers "F.Cu" "F.Mask" "F.Paste")
			(net "PRSNT_CABLE_SWB_B1_N")
		)
	)
	(footprint ""
		(layer "F.Cu")
		(at 486.113836 -470.036144)
		(property "Reference" "JP4003_12"
			(at -2.172716 -3.824224 0)
			(unlocked yes)
			(layer "F.SilkS")
			(effects
				(font
					(size 0.7874 0.5842)
					(thickness 0.1524)
				)
				(justify left)
			)
		)
		(property "Value" ""
			(at 0 0 0)
			(layer "F.Fab")
			(effects
				(font
					(size 1.27 1.27)
				)
			)
		)
		(duplicate_pad_numbers_are_jumpers no)
		(pad "1" smd circle
			(at 0 0)
			(size 0.762 0.762)
			(layers "F.Cu" "F.Mask" "F.Paste")
			(net "Net_8607")
		)
	)
	(footprint ""
		(layer "F.Cu")
		(at 371.23624 -315.66739 90)
		(property "Reference" "PC16"
			(at 0 0 90)
			(layer "F.SilkS")
			(hide yes)
			(effects
				(font
					(size 1.27 1.27)
				)
			)
		)
		(property "Value" ""
			(at 0 0 90)
			(layer "F.Fab")
			(effects
				(font
					(size 1.27 1.27)
				)
			)
		)
		(duplicate_pad_numbers_are_jumpers no)
		(fp_line
			(start 2.750058 0.999998)
			(end -2.750058 0.999998)
			(stroke
				(width 0.1524)
				(type default)
			)
			(layer "F.SilkS")
		)
		(fp_circle
			(center 0 0.999998)
			(end 0 3.750056)
			(stroke
				(width 0.1524)
				(type default)
			)
			(fill no)
			(layer "F.SilkS")
		)
		(fp_poly
			(pts
				(arc
					(start 2.750058 0.999998)
					(mid 0 3.750056)
					(end -2.750058 0.999998)
				)
			)
			(stroke
				(width 0)
				(type default)
			)
			(fill yes)
			(layer "F.SilkS")
		)
		(fp_circle
			(center 0 0.999998)
			(end 0 3.750056)
			(stroke
				(width 0.1)
				(type default)
			)
			(fill no)
			(layer "F.Fab")
		)
		(pad "1" thru_hole rect
			(at 0 0 90)
			(size 1.5748 1.5748)
			(drill 1.0668)
			(layers "*.Cu" "*.Mask")
			(remove_unused_layers no)
			(net "PVCCIN_CPU0")
			(clearance 0)
			(padstack
				(mode front_inner_back)
				(layer "Inner"
					(shape circle)
					(size 1.5748 1.5748)
					(clearance 0)
				)
				(layer "B.Cu"
					(shape rect)
					(size 1.5748 1.5748)
					(clearance 0)
				)
			)
		)
		(pad "2" thru_hole circle
			(at 0 1.999996 90)
			(size 1.5748 1.5748)
			(drill 1.0668)
			(layers "*.Cu" "*.Mask")
			(remove_unused_layers no)
			(net "GND")
			(clearance 0)
		)
	)
	(footprint ""
		(layer "F.Cu")
		(at 131.466844 -132.707126 180)
		(property "Reference" "R3396"
			(at 0 0 180)
			(layer "F.SilkS")
			(hide yes)
			(effects
				(font
					(size 1.27 1.27)
				)
			)
		)
		(property "Value" ""
			(at 0 0 180)
			(layer "F.Fab")
			(effects
				(font
					(size 1.27 1.27)
				)
			)
		)
		(duplicate_pad_numbers_are_jumpers no)
		(fp_line
			(start 0.7874 0.4064)
			(end -0.7874 0.4064)
			(stroke
				(width 0.1524)
				(type default)
			)
			(layer "F.SilkS")
		)
		(fp_line
			(start 0.7874 -0.4064)
			(end 0.7874 0.4064)
			(stroke
				(width 0.1524)
				(type default)
			)
			(layer "F.SilkS")
		)
		(fp_line
			(start -0.7874 0.4064)
			(end -0.7874 -0.4064)
			(stroke
				(width 0.1524)
				(type default)
			)
			(layer "F.SilkS")
		)
		(fp_line
			(start -0.7874 -0.4064)
			(end 0.7874 -0.4064)
			(stroke
				(width 0.1524)
				(type default)
			)
			(layer "F.SilkS")
		)
		(fp_line
			(start 0.67945 0.3048)
			(end 0.120396 0.3048)
			(stroke
				(width 0.1)
				(type default)
			)
			(layer "F.Fab")
		)
		(fp_line
			(start 0.67945 -0.3048)
			(end 0.67945 0.3048)
			(stroke
				(width 0.1)
				(type default)
			)
			(layer "F.Fab")
		)
		(fp_line
			(start 0.12065 -0.2794)
			(end 0.12065 -0.3048)
			(stroke
				(width 0.1)
				(type default)
			)
			(layer "F.Fab")
		)
		(fp_line
			(start 0.12065 -0.3048)
			(end 0.67945 -0.3048)
			(stroke
				(width 0.1)
				(type default)
			)
			(layer "F.Fab")
		)
		(fp_line
			(start 0.120396 0.3048)
			(end 0.120396 0.2794)
			(stroke
				(width 0.1)
				(type default)
			)
			(layer "F.Fab")
		)
		(fp_line
			(start 0.120396 0.2794)
			(end -0.12065 0.2794)
			(stroke
				(width 0.1)
				(type default)
			)
			(layer "F.Fab")
		)
		(fp_line
			(start -0.12065 0.3048)
			(end -0.67945 0.3048)
			(stroke
				(width 0.1)
				(type default)
			)
			(layer "F.Fab")
		)
		(fp_line
			(start -0.12065 0.2794)
			(end -0.12065 0.3048)
			(stroke
				(width 0.1)
				(type default)
			)
			(layer "F.Fab")
		)
		(fp_line
			(start -0.12065 -0.2794)
			(end 0.12065 -0.2794)
			(stroke
				(width 0.1)
				(type default)
			)
			(layer "F.Fab")
		)
		(fp_line
			(start -0.12065 -0.305054)
			(end -0.12065 -0.2794)
			(stroke
				(width 0.1)
				(type default)
			)
			(layer "F.Fab")
		)
		(fp_line
			(start -0.67945 0.3048)
			(end -0.67945 -0.305054)
			(stroke
				(width 0.1)
				(type default)
			)
			(layer "F.Fab")
		)
		(fp_line
			(start -0.67945 -0.305054)
			(end -0.12065 -0.305054)
			(stroke
				(width 0.1)
				(type default)
			)
			(layer "F.Fab")
		)
		(pad "1" smd circle
			(at -0.40005 0 180)
			(size 0 0)
			(layers "F.Cu" "F.Mask" "F.Paste")
			(net "P3V3_AUX")
		)
		(pad "2" smd circle
			(at 0.40005 0 180)
			(size 0 0)
			(layers "F.Cu" "F.Mask" "F.Paste")
			(net "SMB_INA230_3V3AUX_SDA")
		)
	)
	(footprint ""
		(layer "F.Cu")
		(at 144.564608 -106.168698 -90)
		(property "Reference" "R4391"
			(at 0 0 270)
			(layer "F.SilkS")
			(hide yes)
			(effects
				(font
					(size 1.27 1.27)
				)
			)
		)
		(property "Value" ""
			(at 0 0 270)
			(layer "F.Fab")
			(effects
				(font
					(size 1.27 1.27)
				)
			)
		)
		(duplicate_pad_numbers_are_jumpers no)
		(fp_line
			(start -0.7874 0.4064)
			(end -0.7874 -0.4064)
			(stroke
				(width 0.1524)
				(type default)
			)
			(layer "F.SilkS")
		)
		(fp_line
			(start 0.7874 0.4064)
			(end -0.7874 0.4064)
			(stroke
				(width 0.1524)
				(type default)
			)
			(layer "F.SilkS")
		)
		(fp_line
			(start -0.7874 -0.4064)
			(end 0.7874 -0.4064)
			(stroke
				(width 0.1524)
				(type default)
			)
			(layer "F.SilkS")
		)
		(fp_line
			(start 0.7874 -0.4064)
			(end 0.7874 0.4064)
			(stroke
				(width 0.1524)
				(type default)
			)
			(layer "F.SilkS")
		)
		(fp_line
			(start -0.67945 0.3048)
			(end -0.67945 -0.305054)
			(stroke
				(width 0.1)
				(type default)
			)
			(layer "F.Fab")
		)
		(fp_line
			(start -0.12065 0.3048)
			(end -0.67945 0.3048)
			(stroke
				(width 0.1)
				(type default)
			)
			(layer "F.Fab")
		)
		(fp_line
			(start 0.120396 0.3048)
			(end 0.120396 0.2794)
			(stroke
				(width 0.1)
				(type default)
			)
			(layer "F.Fab")
		)
		(fp_line
			(start 0.67945 0.3048)
			(end 0.120396 0.3048)
			(stroke
				(width 0.1)
				(type default)
			)
			(layer "F.Fab")
		)
		(fp_line
			(start -0.12065 0.2794)
			(end -0.12065 0.3048)
			(stroke
				(width 0.1)
				(type default)
			)
			(layer "F.Fab")
		)
		(fp_line
			(start 0.120396 0.2794)
			(end -0.12065 0.2794)
			(stroke
				(width 0.1)
				(type default)
			)
			(layer "F.Fab")
		)
		(fp_line
			(start -0.12065 -0.2794)
			(end 0.12065 -0.2794)
			(stroke
				(width 0.1)
				(type default)
			)
			(layer "F.Fab")
		)
		(fp_line
			(start 0.12065 -0.2794)
			(end 0.12065 -0.3048)
			(stroke
				(width 0.1)
				(type default)
			)
			(layer "F.Fab")
		)
		(fp_line
			(start 0.12065 -0.3048)
			(end 0.67945 -0.3048)
			(stroke
				(width 0.1)
				(type default)
			)
			(layer "F.Fab")
		)
		(fp_line
			(start 0.67945 -0.3048)
			(end 0.67945 0.3048)
			(stroke
				(width 0.1)
				(type default)
			)
			(layer "F.Fab")
		)
		(fp_line
			(start -0.67945 -0.305054)
			(end -0.12065 -0.305054)
			(stroke
				(width 0.1)
				(type default)
			)
			(layer "F.Fab")
		)
		(fp_line
			(start -0.12065 -0.305054)
			(end -0.12065 -0.2794)
			(stroke
				(width 0.1)
				(type default)
			)
			(layer "F.Fab")
		)
		(pad "1" smd circle
			(at -0.40005 0 270)
			(size 0 0)
			(layers "F.Cu" "F.Mask" "F.Paste")
			(net "PD_GTL2014_ERROR_B0")
		)
		(pad "2" smd circle
			(at 0.40005 0 270)
			(size 0 0)
			(layers "F.Cu" "F.Mask" "F.Paste")
			(net "GND")
		)
	)
	(footprint ""
		(layer "F.Cu")
		(at 289.27806 -95.760794)
		(property "Reference" "C629"
			(at 0 0 0)
			(layer "F.SilkS")
			(hide yes)
			(effects
				(font
					(size 1.27 1.27)
				)
			)
		)
		(property "Value" ""
			(at 0 0 0)
			(layer "F.Fab")
			(effects
				(font
					(size 1.27 1.27)
				)
			)
		)
		(duplicate_pad_numbers_are_jumpers no)
		(fp_line
			(start -0.7874 -0.4064)
			(end 0.7874 -0.4064)
			(stroke
				(width 0.1524)
				(type default)
			)
			(layer "F.SilkS")
		)
		(fp_line
			(start -0.7874 0.4064)
			(end -0.7874 -0.4064)
			(stroke
				(width 0.1524)
				(type default)
			)
			(layer "F.SilkS")
		)
		(fp_line
			(start 0.7874 -0.4064)
			(end 0.7874 0.4064)
			(stroke
				(width 0.1524)
				(type default)
			)
			(layer "F.SilkS")
		)
		(fp_line
			(start 0.7874 0.4064)
			(end -0.7874 0.4064)
			(stroke
				(width 0.1524)
				(type default)
			)
			(layer "F.SilkS")
		)
		(fp_line
			(start -0.67945 -0.305054)
			(end -0.12065 -0.305054)
			(stroke
				(width 0.1)
				(type default)
			)
			(layer "F.Fab")
		)
		(fp_line
			(start -0.67945 0.3048)
			(end -0.67945 -0.305054)
			(stroke
				(width 0.1)
				(type default)
			)
			(layer "F.Fab")
		)
		(fp_line
			(start -0.12065 -0.305054)
			(end -0.12065 -0.2794)
			(stroke
				(width 0.1)
				(type default)
			)
			(layer "F.Fab")
		)
		(fp_line
			(start -0.12065 -0.2794)
			(end 0.12065 -0.2794)
			(stroke
				(width 0.1)
				(type default)
			)
			(layer "F.Fab")
		)
		(fp_line
			(start -0.12065 0.2794)
			(end -0.12065 0.3048)
			(stroke
				(width 0.1)
				(type default)
			)
			(layer "F.Fab")
		)
		(fp_line
			(start -0.12065 0.3048)
			(end -0.67945 0.3048)
			(stroke
				(width 0.1)
				(type default)
			)
			(layer "F.Fab")
		)
		(fp_line
			(start 0.120396 0.2794)
			(end -0.12065 0.2794)
			(stroke
				(width 0.1)
				(type default)
			)
			(layer "F.Fab")
		)
		(fp_line
			(start 0.120396 0.3048)
			(end 0.120396 0.2794)
			(stroke
				(width 0.1)
				(type default)
			)
			(layer "F.Fab")
		)
		(fp_line
			(start 0.12065 -0.3048)
			(end 0.67945 -0.3048)
			(stroke
				(width 0.1)
				(type default)
			)
			(layer "F.Fab")
		)
		(fp_line
			(start 0.12065 -0.2794)
			(end 0.12065 -0.3048)
			(stroke
				(width 0.1)
				(type default)
			)
			(layer "F.Fab")
		)
		(fp_line
			(start 0.67945 -0.3048)
			(end 0.67945 0.3048)
			(stroke
				(width 0.1)
				(type default)
			)
			(layer "F.Fab")
		)
		(fp_line
			(start 0.67945 0.3048)
			(end 0.120396 0.3048)
			(stroke
				(width 0.1)
				(type default)
			)
			(layer "F.Fab")
		)
		(pad "1" smd circle
			(at -0.40005 0)
			(size 0 0)
			(layers "F.Cu" "F.Mask" "F.Paste")
			(net "P3V3_AUX")
		)
		(pad "2" smd circle
			(at 0.40005 0)
			(size 0 0)
			(layers "F.Cu" "F.Mask" "F.Paste")
			(net "GND")
		)
	)
)
